# T6G (Grand Teton) — schematic netlist excerpt (pin names and nets, part order shuffled) for the footprints in the layout excerpt that follows; sources: Cadence DE-HDL packaged netlist, KiCad conversion of 04192023_DAF0TMB3IC0_F0TG_MB_C_brd_V02_OCP.brd

C3916  Q_CAP  22UF 4V 20% X6S  pkg C0402  page 74 : A = PVDDCR_SOC_P1 ; B = GND
C2110  Q_CAP  22UF 4V 20% X6S  pkg C0402  page 74 : A = PVDDIO_P1 ; B = GND
C6684  Q_CAP_DIFFBUS  DIFF BUS_0.22UF 6.3V 20% X6S  pkg C0201  page 330 : \1\ = P5E_CPU1_P1_TX_BUF_C_DN<11> ; \2\ = P5E_CPU1_P1_TX_BUF_DN<11>

(kicad_pcb
	(version 20260206)
	(generator "pcbnew")
	(generator_version "10.0")
	(general
		(thickness 1.6)
		(legacy_teardrops no)
	)
	(paper "A4")
	(title_block
		(title "04192023_DAF0TMB3IC0_F0TG_MB_C_brd_V02_OCP.brd")
		(comment 1 "Grand Teton / footprints 6702-6704 of 8354")
	)
	(layers
		(0 "F.Cu" signal "TOP")
		(4 "In1.Cu" signal "GND")
		(6 "In2.Cu" signal "IN1")
		(8 "In3.Cu" signal "GND1")
		(10 "In4.Cu" signal "IN2")
		(12 "In5.Cu" signal "GND2")
		(14 "In6.Cu" signal "IN3")
		(16 "In7.Cu" signal "GND3")
		(18 "In8.Cu" signal "VCC")
		(20 "In9.Cu" signal "VCC1")
		(22 "In10.Cu" signal "GND4")
		(24 "In11.Cu" signal "IN4")
		(26 "In12.Cu" signal "GND5")
		(28 "In13.Cu" signal "IN5")
		(30 "In14.Cu" signal "GND6")
		(32 "In15.Cu" signal "IN6")
		(34 "In16.Cu" signal "GND7")
		(2 "B.Cu" signal "BOTTOM")
		(9 "F.Adhes" user "F.Adhesive")
		(11 "B.Adhes" user "B.Adhesive")
		(13 "F.Paste" user "Package Geometry/Pastemask Top")
		(15 "B.Paste" user "Package Geometry/Pastemask Bottom")
		(5 "F.SilkS" user "Ref Des/Silkscreen Top")
		(7 "B.SilkS" user "Ref Des/Silkscreen Bottom")
		(1 "F.Mask" user "Board Geometry/Soldermask Top")
		(3 "B.Mask" user "Board Geometry/Soldermask Bottom")
		(17 "Dwgs.User" user "User.Drawings")
		(19 "Cmts.User" user "User.Comments")
		(21 "Eco1.User" user "User.Eco1")
		(23 "Eco2.User" user "User.Eco2")
		(25 "Edge.Cuts" user "Board Geometry/Outline")
		(27 "Margin" user)
		(31 "F.CrtYd" user "Package Geometry/Place Bound Top")
		(29 "B.CrtYd" user "Package Geometry/Place Bound Bottom")
		(35 "F.Fab" user "Ref Des/Assembly Top")
		(33 "B.Fab" user "Ref Des/Assembly Bottom")
	)
	(footprint ""
		(layer "B.Cu")
		(at 121.685812 -258.830318)
		(property "Reference" "C3916"
			(at 0 0 0)
			(layer "B.SilkS")
			(hide yes)
			(effects
				(font
					(size 1.27 1.27)
				)
				(justify mirror)
			)
		)
		(property "Value" ""
			(at 0 0 0)
			(layer "B.Fab")
			(effects
				(font
					(size 1.27 1.27)
				)
				(justify mirror)
			)
		)
		(duplicate_pad_numbers_are_jumpers no)
		(fp_line
			(start -0.7874 -0.4064)
			(end -0.7874 0.4064)
			(stroke
				(width 0.1524)
				(type default)
			)
			(layer "B.SilkS")
		)
		(fp_line
			(start -0.7874 0.4064)
			(end 0.7874 0.4064)
			(stroke
				(width 0.1524)
				(type default)
			)
			(layer "B.SilkS")
		)
		(fp_line
			(start 0.7874 -0.4064)
			(end -0.7874 -0.4064)
			(stroke
				(width 0.1524)
				(type default)
			)
			(layer "B.SilkS")
		)
		(fp_line
			(start 0.7874 0.4064)
			(end 0.7874 -0.4064)
			(stroke
				(width 0.1524)
				(type default)
			)
			(layer "B.SilkS")
		)
		(fp_line
			(start -0.67945 -0.3048)
			(end -0.67945 0.3048)
			(stroke
				(width 0.1)
				(type default)
			)
			(layer "B.Fab")
		)
		(fp_line
			(start -0.67945 0.3048)
			(end -0.120396 0.3048)
			(stroke
				(width 0.1)
				(type default)
			)
			(layer "B.Fab")
		)
		(fp_line
			(start -0.12065 -0.3048)
			(end -0.67945 -0.3048)
			(stroke
				(width 0.1)
				(type default)
			)
			(layer "B.Fab")
		)
		(fp_line
			(start -0.12065 -0.2794)
			(end -0.12065 -0.3048)
			(stroke
				(width 0.1)
				(type default)
			)
			(layer "B.Fab")
		)
		(fp_line
			(start -0.120396 0.2794)
			(end 0.12065 0.2794)
			(stroke
				(width 0.1)
				(type default)
			)
			(layer "B.Fab")
		)
		(fp_line
			(start -0.120396 0.3048)
			(end -0.120396 0.2794)
			(stroke
				(width 0.1)
				(type default)
			)
			(layer "B.Fab")
		)
		(fp_line
			(start 0.12065 -0.305054)
			(end 0.12065 -0.2794)
			(stroke
				(width 0.1)
				(type default)
			)
			(layer "B.Fab")
		)
		(fp_line
			(start 0.12065 -0.2794)
			(end -0.12065 -0.2794)
			(stroke
				(width 0.1)
				(type default)
			)
			(layer "B.Fab")
		)
		(fp_line
			(start 0.12065 0.2794)
			(end 0.12065 0.3048)
			(stroke
				(width 0.1)
				(type default)
			)
			(layer "B.Fab")
		)
		(fp_line
			(start 0.12065 0.3048)
			(end 0.67945 0.3048)
			(stroke
				(width 0.1)
				(type default)
			)
			(layer "B.Fab")
		)
		(fp_line
			(start 0.67945 -0.305054)
			(end 0.12065 -0.305054)
			(stroke
				(width 0.1)
				(type default)
			)
			(layer "B.Fab")
		)
		(fp_line
			(start 0.67945 0.3048)
			(end 0.67945 -0.305054)
			(stroke
				(width 0.1)
				(type default)
			)
			(layer "B.Fab")
		)
		(pad "1" smd circle
			(at 0.40005 0 180)
			(size 0 0)
			(layers "B.Cu" "B.Mask" "B.Paste")
			(net "PVDDCR_SOC_P1")
		)
		(pad "2" smd circle
			(at -0.40005 0 180)
			(size 0 0)
			(layers "B.Cu" "B.Mask" "B.Paste")
			(net "GND")
		)
	)
	(footprint ""
		(layer "B.Cu")
		(at 102.378764 -257.930396 180)
		(property "Reference" "C2110"
			(at 0 0 0)
			(layer "B.SilkS")
			(hide yes)
			(effects
				(font
					(size 1.27 1.27)
				)
				(justify mirror)
			)
		)
		(property "Value" ""
			(at 0 0 0)
			(layer "B.Fab")
			(effects
				(font
					(size 1.27 1.27)
				)
				(justify mirror)
			)
		)
		(duplicate_pad_numbers_are_jumpers no)
		(fp_line
			(start 0.7874 0.4064)
			(end 0.7874 -0.4064)
			(stroke
				(width 0.1524)
				(type default)
			)
			(layer "B.SilkS")
		)
		(fp_line
			(start 0.7874 -0.4064)
			(end -0.7874 -0.4064)
			(stroke
				(width 0.1524)
				(type default)
			)
			(layer "B.SilkS")
		)
		(fp_line
			(start -0.7874 0.4064)
			(end 0.7874 0.4064)
			(stroke
				(width 0.1524)
				(type default)
			)
			(layer "B.SilkS")
		)
		(fp_line
			(start -0.7874 -0.4064)
			(end -0.7874 0.4064)
			(stroke
				(width 0.1524)
				(type default)
			)
			(layer "B.SilkS")
		)
		(fp_line
			(start 0.67945 0.3048)
			(end 0.67945 -0.305054)
			(stroke
				(width 0.1)
				(type default)
			)
			(layer "B.Fab")
		)
		(fp_line
			(start 0.67945 -0.305054)
			(end 0.12065 -0.305054)
			(stroke
				(width 0.1)
				(type default)
			)
			(layer "B.Fab")
		)
		(fp_line
			(start 0.12065 0.3048)
			(end 0.67945 0.3048)
			(stroke
				(width 0.1)
				(type default)
			)
			(layer "B.Fab")
		)
		(fp_line
			(start 0.12065 0.2794)
			(end 0.12065 0.3048)
			(stroke
				(width 0.1)
				(type default)
			)
			(layer "B.Fab")
		)
		(fp_line
			(start 0.12065 -0.2794)
			(end -0.12065 -0.2794)
			(stroke
				(width 0.1)
				(type default)
			)
			(layer "B.Fab")
		)
		(fp_line
			(start 0.12065 -0.305054)
			(end 0.12065 -0.2794)
			(stroke
				(width 0.1)
				(type default)
			)
			(layer "B.Fab")
		)
		(fp_line
			(start -0.120396 0.3048)
			(end -0.120396 0.2794)
			(stroke
				(width 0.1)
				(type default)
			)
			(layer "B.Fab")
		)
		(fp_line
			(start -0.120396 0.2794)
			(end 0.12065 0.2794)
			(stroke
				(width 0.1)
				(type default)
			)
			(layer "B.Fab")
		)
		(fp_line
			(start -0.12065 -0.2794)
			(end -0.12065 -0.3048)
			(stroke
				(width 0.1)
				(type default)
			)
			(layer "B.Fab")
		)
		(fp_line
			(start -0.12065 -0.3048)
			(end -0.67945 -0.3048)
			(stroke
				(width 0.1)
				(type default)
			)
			(layer "B.Fab")
		)
		(fp_line
			(start -0.67945 0.3048)
			(end -0.120396 0.3048)
			(stroke
				(width 0.1)
				(type default)
			)
			(layer "B.Fab")
		)
		(fp_line
			(start -0.67945 -0.3048)
			(end -0.67945 0.3048)
			(stroke
				(width 0.1)
				(type default)
			)
			(layer "B.Fab")
		)
		(pad "1" smd circle
			(at 0.40005 0)
			(size 0 0)
			(layers "B.Cu" "B.Mask" "B.Paste")
			(net "PVDDIO_P1")
		)
		(pad "2" smd circle
			(at -0.40005 0)
			(size 0 0)
			(layers "B.Cu" "B.Mask" "B.Paste")
			(net "GND")
		)
	)
	(footprint ""
		(layer "B.Cu")
		(at 82.996024 -408.517344 90)
		(property "Reference" "C6684"
			(at 0 0 90)
			(layer "B.SilkS")
			(hide yes)
			(effects
				(font
					(size 1.27 1.27)
				)
				(justify mirror)
			)
		)
		(property "Value" ""
			(at 0 0 90)
			(layer "B.Fab")
			(effects
				(font
					(size 1.27 1.27)
				)
				(justify mirror)
			)
		)
		(duplicate_pad_numbers_are_jumpers no)
		(fp_line
			(start 0.299974 -0.150114)
			(end -0.299974 -0.150114)
			(stroke
				(width 0.1)
				(type default)
			)
			(layer "B.Fab")
		)
		(fp_line
			(start -0.299974 -0.150114)
			(end -0.299974 0.150114)
			(stroke
				(width 0.1)
				(type default)
			)
			(layer "B.Fab")
		)
		(fp_line
			(start 0.299974 0.150114)
			(end 0.299974 -0.150114)
			(stroke
				(width 0.1)
				(type default)
			)
			(layer "B.Fab")
		)
		(fp_line
			(start -0.299974 0.150114)
			(end 0.299974 0.150114)
			(stroke
				(width 0.1)
				(type default)
			)
			(layer "B.Fab")
		)
		(pad "1" smd rect
			(at 0.2667 0 270)
			(size 0.3048 0.381)
			(layers "B.Cu" "B.Mask" "B.Paste")
			(net "P5E_CPU1_P1_TX_BUF_C_DN<11>")
		)
		(pad "2" smd rect
			(at -0.2667 0 270)
			(size 0.3048 0.381)
			(layers "B.Cu" "B.Mask" "B.Paste")
			(net "P5E_CPU1_P1_TX_BUF_DN<11>")
		)
	)
)
